(kicad_pcb
	(version 20260206)
	(generator "pcbnew")
	(generator_version "10.0")
	(general
		(thickness 1.21888)
		(legacy_teardrops no)
	)
	(paper "A4")
	(title_block
		(title "timecard-v8 — TimeCard-DC-V8_EXP.PcbDoc")
		(comment 1 "Time Appliance Project (Time Card) / footprints 245-250 of 288")
	)
	(layers
		(0 "F.Cu" signal "TOP")
		(4 "In1.Cu" signal "SGND")
		(6 "In2.Cu" signal "IN1")
		(8 "In3.Cu" signal "IN2")
		(10 "In4.Cu" signal "SGND1")
		(2 "B.Cu" signal "BOTTOM")
		(9 "F.Adhes" user "F.Adhesive")
		(11 "B.Adhes" user "B.Adhesive")
		(13 "F.Paste" user "Top Paste")
		(15 "B.Paste" user "Bottom Paste")
		(5 "F.SilkS" user "Top Overlay")
		(7 "B.SilkS" user "Bottom Overlay")
		(1 "F.Mask" user "Top Solder")
		(3 "B.Mask" user "Bottom Solder")
		(17 "Dwgs.User" user "User.Drawings")
		(19 "Cmts.User" user "User.Comments")
		(21 "Eco1.User" user "User.Eco1")
		(23 "Eco2.User" user "User.Eco2")
		(25 "Edge.Cuts" user)
		(27 "Margin" user)
		(31 "F.CrtYd" user "Top Courtyard")
		(29 "B.CrtYd" user "Bottom Courtyard")
		(35 "F.Fab" user "Top Component Center")
		(33 "B.Fab" user "Bottom Component Center")
	)
	(footprint "SA53:SA53"
		(locked yes)
		(layer "F.Cu")
		(at 120.49358 116.5662 180)
		(property "Reference" "U10"
			(at -22.46112 27.623069 0)
			(unlocked yes)
			(layer "F.SilkS")
			(effects
				(font
					(size 0.762 0.762)
					(thickness 0.2286)
				)
			)
		)
		(property "Value" "MAC-SA5X"
			(at -18.327985 28.437071 180)
			(unlocked yes)
			(layer "F.SilkS")
			(hide yes)
			(effects
				(font
					(size 0.762 0.762)
					(thickness 0.2286)
				)
			)
		)
		(sheetname "MAC")
		(sheetfile "MAC.kicad_sch")
		(duplicate_pad_numbers_are_jumpers no)
		(fp_line
			(start 26.26748 26.75)
			(end -24.53252 26.75)
			(stroke
				(width 0.254)
				(type solid)
			)
			(layer "F.SilkS")
		)
		(fp_line
			(start 26.26748 -24.05)
			(end 26.26748 26.75)
			(stroke
				(width 0.254)
				(type solid)
			)
			(layer "F.SilkS")
		)
		(fp_line
			(start 26.26748 -24.05)
			(end -24.53252 -24.05)
			(stroke
				(width 0.254)
				(type solid)
			)
			(layer "F.SilkS")
		)
		(fp_line
			(start -24.53252 -24.05)
			(end -24.53252 26.75)
			(stroke
				(width 0.254)
				(type solid)
			)
			(layer "F.SilkS")
		)
		(fp_circle
			(center -15.74749 3.64128)
			(end -15.74749 3.76828)
			(stroke
				(width 0.254)
				(type solid)
			)
			(fill no)
			(layer "F.SilkS")
		)
		(pad "" np_thru_hole circle
			(at -15.05499 -16.94261 180)
			(size 6.096 6.096)
			(drill 2.54)
			(layers "*.Cu" "*.Mask")
			(thermal_bridge_angle 90)
			(padstack
				(mode front_inner_back)
				(layer "Inner"
					(shape circle)
					(size 3.048 3.048)
				)
				(layer "B.Cu"
					(shape circle)
					(size 6.096 6.096)
				)
			)
		)
		(pad "" np_thru_hole circle
			(at -14.98753 19.5926 180)
			(size 6.096 6.096)
			(drill 2.54)
			(layers "*.Cu" "*.Mask")
			(thermal_bridge_angle 90)
			(padstack
				(mode front_inner_back)
				(layer "Inner"
					(shape circle)
					(size 3.048 3.048)
				)
				(layer "B.Cu"
					(shape circle)
					(size 6.096 6.096)
				)
			)
		)
		(pad "" np_thru_hole circle
			(at 16.08749 22.666 180)
			(size 6.096 6.096)
			(drill 2.54)
			(layers "*.Cu" "*.Mask")
			(thermal_bridge_angle 90)
			(padstack
				(mode front_inner_back)
				(layer "Inner"
					(shape circle)
					(size 3.048 3.048)
				)
				(layer "B.Cu"
					(shape circle)
					(size 6.096 6.096)
				)
			)
		)
		(pad "" np_thru_hole circle
			(at 16.72249 -18.442 180)
			(size 6.096 6.096)
			(drill 2.54)
			(layers "*.Cu" "*.Mask")
			(thermal_bridge_angle 90)
			(padstack
				(mode front_inner_back)
				(layer "Inner"
					(shape circle)
					(size 3.048 3.048)
				)
				(layer "B.Cu"
					(shape circle)
					(size 6.096 6.096)
				)
			)
		)
		(pad "1" smd rect
			(at -17.16749 3.64128 270)
			(size 0.25 1.8)
			(layers "F.Cu" "F.Mask" "F.Paste")
			(net "MAC_PPS_IN1+")
		)
		(pad "2" smd rect
			(at -21.16749 3.64128 270)
			(size 0.25 1.8)
			(layers "F.Cu" "F.Mask" "F.Paste")
			(net "MAC_USB+")
		)
		(pad "3" smd rect
			(at -17.16749 3.13328 270)
			(size 0.25 1.8)
			(layers "F.Cu" "F.Mask" "F.Paste")
			(net "MAC_PPS_IN1-")
		)
		(pad "4" smd rect
			(at -21.16749 3.13328 270)
			(size 0.25 1.8)
			(layers "F.Cu" "F.Mask" "F.Paste")
			(net "MAC_USB-")
		)
		(pad "5" smd rect
			(at -17.16749 2.62528 270)
			(size 0.25 1.8)
			(layers "F.Cu" "F.Mask" "F.Paste")
			(net "MAC_PPS_IN0+")
		)
		(pad "6" smd rect
			(at -21.16749 2.62528 270)
			(size 0.25 1.8)
			(layers "F.Cu" "F.Mask" "F.Paste")
			(net "MAC_USB_PWR")
		)
		(pad "7" smd rect
			(at -17.16749 2.11728 270)
			(size 0.25 1.8)
			(layers "F.Cu" "F.Mask" "F.Paste")
			(net "MAC_PPS_IN0-")
		)
		(pad "8" smd rect
			(at -21.16749 2.11728 270)
			(size 0.25 1.8)
			(layers "F.Cu" "F.Mask" "F.Paste")
			(net "GND")
		)
		(pad "9" smd rect
			(at -17.16749 1.60928 270)
			(size 0.25 1.8)
			(layers "F.Cu" "F.Mask" "F.Paste")
			(net "GND")
		)
		(pad "10" smd rect
			(at -21.16749 1.60928 270)
			(size 0.25 1.8)
			(layers "F.Cu" "F.Mask" "F.Paste")
		)
		(pad "11" smd rect
			(at -17.16749 1.10128 270)
			(size 0.25 1.8)
			(layers "F.Cu" "F.Mask" "F.Paste")
		)
		(pad "12" smd rect
			(at -21.16749 1.10128 270)
			(size 0.25 1.8)
			(layers "F.Cu" "F.Mask" "F.Paste")
		)
		(pad "13" smd rect
			(at -17.16749 0.59328 270)
			(size 0.25 1.8)
			(layers "F.Cu" "F.Mask" "F.Paste")
		)
		(pad "14" smd rect
			(at -21.16749 0.59328 270)
			(size 0.25 1.8)
			(layers "F.Cu" "F.Mask" "F.Paste")
		)
		(pad "15" smd rect
			(at -17.16749 0.08528 270)
			(size 0.25 1.8)
			(layers "F.Cu" "F.Mask" "F.Paste")
			(net "GND")
		)
		(pad "16" smd rect
			(at -21.16749 0.08528 270)
			(size 0.25 1.8)
			(layers "F.Cu" "F.Mask" "F.Paste")
		)
		(pad "17" smd rect
			(at -17.16749 -0.42272 270)
			(size 0.25 1.8)
			(layers "F.Cu" "F.Mask" "F.Paste")
			(net "MAC_PPS_OUT+")
		)
		(pad "18" smd rect
			(at -21.16749 -0.42272 270)
			(size 0.25 1.8)
			(layers "F.Cu" "F.Mask" "F.Paste")
		)
		(pad "19" smd rect
			(at -17.16749 -0.93072 270)
			(size 0.25 1.8)
			(layers "F.Cu" "F.Mask" "F.Paste")
			(net "MAC_PPS_OUT-")
		)
		(pad "20" smd rect
			(at -21.16749 -0.93072 270)
			(size 0.25 1.8)
			(layers "F.Cu" "F.Mask" "F.Paste")
			(net "MAC_ALARM")
		)
		(pad "P1" thru_hole circle
			(at 21.16748 21.65 90)
			(size 2.54 2.54)
			(drill 2.0066)
			(layers "*.Cu" "*.Mask")
			(remove_unused_layers no)
			(net "MAC_FREQ_CTRL")
			(thermal_bridge_angle 90)
		)
		(pad "P2" thru_hole circle
			(at 21.16748 1.35 90)
			(size 2.54 2.54)
			(drill 2.0066)
			(layers "*.Cu" "*.Mask")
			(remove_unused_layers no)
			(net "GND")
			(thermal_bridge_angle 90)
		)
		(pad "P3" thru_hole circle
			(at 21.16748 -18.95 90)
			(size 2.54 2.54)
			(drill 2.0066)
			(layers "*.Cu" "*.Mask")
			(remove_unused_layers no)
			(net "MAC_RF_OUT")
			(thermal_bridge_angle 90)
		)
		(pad "P4" thru_hole circle
			(at -19.43252 -18.95 90)
			(size 2.54 2.54)
			(drill 2.0066)
			(layers "*.Cu" "*.Mask")
			(remove_unused_layers no)
			(net "GND")
			(thermal_bridge_angle 90)
		)
		(pad "P5" thru_hole circle
			(at -19.43252 21.65 90)
			(size 2.54 2.54)
			(drill 2.0066)
			(layers "*.Cu" "*.Mask")
			(remove_unused_layers no)
			(net "MAC_VCC")
			(thermal_bridge_angle 90)
		)
		(pad "P6" thru_hole circle
			(at -17.33252 -21.65 90)
			(size 2.54 2.54)
			(drill 2.0066)
			(layers "*.Cu" "*.Mask")
			(remove_unused_layers no)
			(net "MAC_BITE")
			(thermal_bridge_angle 90)
		)
		(pad "P7" thru_hole circle
			(at -14.33252 -21.65 90)
			(size 2.54 2.54)
			(drill 2.0066)
			(layers "*.Cu" "*.Mask")
			(remove_unused_layers no)
			(net "MAC_RX")
			(thermal_bridge_angle 90)
		)
		(pad "P8" thru_hole circle
			(at -11.33252 -21.65 90)
			(size 2.54 2.54)
			(drill 2.0066)
			(layers "*.Cu" "*.Mask")
			(remove_unused_layers no)
			(net "MAC_TX")
			(thermal_bridge_angle 90)
		)
		(pad "P9" thru_hole circle
			(at -8.28452 -21.65 90)
			(size 2.54 2.54)
			(drill 2.0066)
			(layers "*.Cu" "*.Mask")
			(remove_unused_layers no)
			(net "MAC_PPS_IN")
			(thermal_bridge_angle 90)
		)
		(pad "P10" thru_hole circle
			(at -5.23652 -21.65 90)
			(size 2.54 2.54)
			(drill 2.0066)
			(layers "*.Cu" "*.Mask")
			(remove_unused_layers no)
			(net "MAC_PPS_OUT")
			(thermal_bridge_angle 90)
		)
		(zone
			(layer "F.Cu")
			(hatch edge 0.5)
			(connect_pads
				(clearance 0)
			)
			(min_thickness 0.25)
			(keepout
				(tracks allowed)
				(vias allowed)
				(pads allowed)
				(copperpour not_allowed)
				(footprints allowed)
			)
			(placement
				(enabled no)
				(sheetname "")
			)
			(fill
				(thermal_gap 0.5)
				(thermal_bridge_width 0.5)
				(island_removal_mode 0)
			)
			(polygon
				(pts
					(xy 135.99358 120.0662) (xy 135.99359 110.0662) (xy 143.49359 110.0662) (xy 143.49358 120.0662)
				)
			)
		)
		(zone
			(layer "F.Cu")
			(hatch edge 0.5)
			(connect_pads
				(clearance 0)
			)
			(min_thickness 0.25)
			(keepout
				(tracks allowed)
				(vias allowed)
				(pads allowed)
				(copperpour not_allowed)
				(footprints allowed)
			)
			(placement
				(enabled no)
				(sheetname "")
			)
			(fill
				(thermal_gap 0.5)
				(thermal_bridge_width 0.5)
				(island_removal_mode 0)
			)
			(polygon
				(pts
					(xy 144.99358 121.5662) (xy 133.49358 121.5662) (xy 133.49358 109.0662) (xy 144.99358 109.0662)
				)
			)
		)
	)
	(footprint "Vault:CAPC1005X56X25NL10T15"
		(layer "F.Cu")
		(at 189.6261 90.0162 180)
		(property "Reference" "C32"
			(at -2.5286 -0.326931 0)
			(unlocked yes)
			(layer "F.SilkS")
			(effects
				(font
					(size 0.762 0.762)
					(thickness 0.2286)
				)
			)
		)
		(property "Value" "0.1uF_0402"
			(at 2.06904 2.567191 180)
			(unlocked yes)
			(layer "F.SilkS")
			(hide yes)
			(effects
				(font
					(size 0.762 0.762)
					(thickness 0.2286)
				)
			)
		)
		(sheetname "GPS_IMU_SENSORS")
		(sheetfile "GPS_IMU_SENSORS.kicad_sch")
		(duplicate_pad_numbers_are_jumpers no)
		(pad "1" smd rect
			(at -0.44 0 270)
			(size 0.64 0.68)
			(layers "F.Cu" "F.Mask" "F.Paste")
			(net "BNO_XIN32_C")
		)
		(pad "2" smd rect
			(at 0.44 0 270)
			(size 0.64 0.68)
			(layers "F.Cu" "F.Mask" "F.Paste")
			(net "BNO_XIN32")
		)
	)
	(footprint "Vault:FP-0402-L_1_0_1-W_0_5_0_1-IPC_C"
		(layer "F.Cu")
		(at 214.8261 78.5162 90)
		(property "Reference" "C95"
			(at 5.3286 0.126931 90)
			(unlocked yes)
			(layer "F.SilkS")
			(effects
				(font
					(size 0.762 0.762)
					(thickness 0.2286)
				)
			)
		)
		(property "Value" "0.1uF_25V_0402"
			(at -2.465551 9.839205 0)
			(unlocked yes)
			(layer "F.SilkS")
			(hide yes)
			(effects
				(font
					(size 0.762 0.762)
					(thickness 0.2286)
				)
			)
		)
		(sheetname "USBUart_DipSelects")
		(sheetfile "USBUart_DipSelects.kicad_sch")
		(duplicate_pad_numbers_are_jumpers no)
		(fp_line
			(start -0.65607 -0.7)
			(end 0.65607 -0.7)
			(stroke
				(width 0.2)
				(type solid)
			)
			(layer "F.SilkS")
		)
		(fp_line
			(start -0.65607 0.7)
			(end 0.65607 0.7)
			(stroke
				(width 0.2)
				(type solid)
			)
			(layer "F.SilkS")
		)
		(fp_line
			(start 0.75607 -0.4)
			(end 0.75607 0.4)
			(stroke
				(width 0.2)
				(type solid)
			)
			(layer "F.CrtYd")
		)
		(fp_line
			(start -0.75606 -0.4)
			(end 0.75607 -0.4)
			(stroke
				(width 0.2)
				(type solid)
			)
			(layer "F.CrtYd")
		)
		(fp_line
			(start -0.75606 -0.4)
			(end -0.75606 0.4)
			(stroke
				(width 0.2)
				(type solid)
			)
			(layer "F.CrtYd")
		)
		(fp_line
			(start -0.75606 0.4)
			(end 0.75607 0.4)
			(stroke
				(width 0.2)
				(type solid)
			)
			(layer "F.CrtYd")
		)
		(fp_line
			(start 0 -0.5)
			(end 0 0.5)
			(stroke
				(width 0.1)
				(type solid)
			)
			(layer "F.Fab")
		)
		(fp_line
			(start 0.75607 -0.4)
			(end 0.75607 0.4)
			(stroke
				(width 0.2)
				(type solid)
			)
			(layer "F.Fab")
		)
		(fp_line
			(start -0.75606 -0.4)
			(end 0.75607 -0.4)
			(stroke
				(width 0.2)
				(type solid)
			)
			(layer "F.Fab")
		)
		(fp_line
			(start -0.75606 -0.4)
			(end -0.75606 0.4)
			(stroke
				(width 0.2)
				(type solid)
			)
			(layer "F.Fab")
		)
		(fp_line
			(start -0.5 0)
			(end 0.5 0)
			(stroke
				(width 0.1)
				(type solid)
			)
			(layer "F.Fab")
		)
		(fp_line
			(start -0.75606 0.4)
			(end 0.75607 0.4)
			(stroke
				(width 0.2)
				(type solid)
			)
			(layer "F.Fab")
		)
		(fp_text user "${REFERENCE}"
			(at -0.00001 0.09601 90)
			(unlocked yes)
			(layer "F.Fab")
			(effects
				(font
					(face "Arial")
					(size 0.63 0.63)
					(thickness 0.1)
				)
				(justify left bottom)
			)
		)
		(pad "1" smd rect
			(at -0.36553 0 90)
			(size 0.58106 0.51213)
			(layers "F.Cu" "F.Mask" "F.Paste")
			(net "+3.3V")
			(solder_mask_margin 0)
			(solder_paste_margin 0)
		)
		(pad "2" smd rect
			(at 0.36554 0 90)
			(size 0.58106 0.51213)
			(layers "F.Cu" "F.Mask" "F.Paste")
			(net "GND")
			(solder_mask_margin 0)
			(solder_paste_margin 0)
		)
	)
	(footprint "Vault:FP-0402-L_1_0_0_05-W_0_5-IPC_A"
		(layer "F.Cu")
		(at 231.9261 125.3162)
		(property "Reference" "C82"
			(at 2.5286 0.026921 0)
			(unlocked yes)
			(layer "F.SilkS")
			(effects
				(font
					(size 0.762 0.762)
					(thickness 0.2286)
				)
			)
		)
		(property "Value" "1uF_16V_0402"
			(at -2.744951 8.290305 270)
			(unlocked yes)
			(layer "F.SilkS")
			(hide yes)
			(effects
				(font
					(size 0.762 0.762)
					(thickness 0.2286)
				)
			)
		)
		(sheetname "POWER")
		(sheetfile "POWER.kicad_sch")
		(duplicate_pad_numbers_are_jumpers no)
		(fp_line
			(start -0.83624 -0.73624)
			(end 0.83624 -0.73624)
			(stroke
				(width 0.2)
				(type solid)
			)
			(layer "F.SilkS")
		)
		(fp_line
			(start -0.83624 0.73624)
			(end 0.83624 0.73624)
			(stroke
				(width 0.2)
				(type solid)
			)
			(layer "F.SilkS")
		)
		(fp_line
			(start -1.03624 -0.53624)
			(end 1.03624 -0.53624)
			(stroke
				(width 0.2)
				(type solid)
			)
			(layer "F.CrtYd")
		)
		(fp_line
			(start -1.03624 0.53624)
			(end -1.03624 -0.53624)
			(stroke
				(width 0.2)
				(type solid)
			)
			(layer "F.CrtYd")
		)
		(fp_line
			(start -1.03624 0.53624)
			(end 1.03624 0.53624)
			(stroke
				(width 0.2)
				(type solid)
			)
			(layer "F.CrtYd")
		)
		(fp_line
			(start 1.03624 0.53624)
			(end 1.03624 -0.53624)
			(stroke
				(width 0.2)
				(type solid)
			)
			(layer "F.CrtYd")
		)
		(fp_line
			(start -1.03624 -0.53624)
			(end 1.03624 -0.53624)
			(stroke
				(width 0.2)
				(type solid)
			)
			(layer "F.Fab")
		)
		(fp_line
			(start -1.03624 0.53624)
			(end -1.03624 -0.53624)
			(stroke
				(width 0.2)
				(type solid)
			)
			(layer "F.Fab")
		)
		(fp_line
			(start -1.03624 0.53624)
			(end 1.03624 0.53624)
			(stroke
				(width 0.2)
				(type solid)
			)
			(layer "F.Fab")
		)
		(fp_line
			(start -0.5 0)
			(end 0.5 0)
			(stroke
				(width 0.1)
				(type solid)
			)
			(layer "F.Fab")
		)
		(fp_line
			(start 0 0.5)
			(end 0 -0.5)
			(stroke
				(width 0.1)
				(type solid)
			)
			(layer "F.Fab")
		)
		(fp_line
			(start 1.03624 0.53624)
			(end 1.03624 -0.53624)
			(stroke
				(width 0.2)
				(type solid)
			)
			(layer "F.Fab")
		)
		(fp_text user "${REFERENCE}"
			(at -0.00001 0.09602 360)
			(unlocked yes)
			(layer "F.Fab")
			(effects
				(font
					(face "Arial")
					(size 0.63 0.63)
					(thickness 0.1)
				)
				(justify left bottom)
			)
		)
		(pad "1" smd rect
			(at -0.47856 0)
			(size 0.71535 0.67248)
			(layers "F.Cu" "F.Mask" "F.Paste")
			(net "+3.3V")
			(solder_mask_margin 0)
			(solder_paste_margin 0)
		)
		(pad "2" smd rect
			(at 0.47856 0)
			(size 0.71535 0.67248)
			(layers "F.Cu" "F.Mask" "F.Paste")
			(net "GND")
			(solder_mask_margin 0)
			(solder_paste_margin 0)
		)
	)
	(footprint "Vault:RESC1005X40X25NL05T10"
		(layer "F.Cu")
		(at 211.3261 127.6162)
		(property "Reference" "R75"
			(at -0.0714 2.226931 0)
			(unlocked yes)
			(layer "F.SilkS")
			(effects
				(font
					(size 0.762 0.762)
					(thickness 0.2286)
				)
			)
		)
		(property "Value" "19.6K_1%_0402"
			(at -2.732271 9.40766 270)
			(unlocked yes)
			(layer "F.SilkS")
			(hide yes)
			(effects
				(font
					(size 0.762 0.762)
					(thickness 0.2286)
				)
			)
		)
		(sheetname "POWER")
		(sheetfile "POWER.kicad_sch")
		(duplicate_pad_numbers_are_jumpers no)
		(pad "1" smd rect
			(at -0.425 0 90)
			(size 0.55 0.6)
			(layers "F.Cu" "F.Mask" "F.Paste")
			(net "NetC74_1")
		)
		(pad "2" smd rect
			(at 0.425 0 90)
			(size 0.55 0.6)
			(layers "F.Cu" "F.Mask" "F.Paste")
			(net "NetL2_1")
		)
	)
	(footprint "Vault:FP-MK212BG-MFG"
		(layer "F.Cu")
		(at 94.7261 65.5162 90)
		(property "Reference" "C41"
			(at 3.171395 -0.026931 270)
			(unlocked yes)
			(layer "F.SilkS")
			(effects
				(font
					(size 0.762 0.762)
					(thickness 0.2286)
				)
			)
		)
		(property "Value" "10uF"
			(at 1.45964 2.478271 90)
			(unlocked yes)
			(layer "F.SilkS")
			(hide yes)
			(effects
				(font
					(size 0.762 0.762)
					(thickness 0.2286)
				)
			)
		)
		(sheetname "GPS_IMU_SENSORS")
		(sheetfile "GPS_IMU_SENSORS.kicad_sch")
		(duplicate_pad_numbers_are_jumpers no)
		(fp_line
			(start -0.125 -0.725)
			(end 0.125 -0.725)
			(stroke
				(width 0.2)
				(type solid)
			)
			(layer "F.SilkS")
		)
		(fp_line
			(start -0.125 0.725)
			(end 0.125 0.725)
			(stroke
				(width 0.2)
				(type solid)
			)
			(layer "F.SilkS")
		)
		(fp_line
			(start 1.6 -0.825)
			(end 1.6 0.825)
			(stroke
				(width 0.2)
				(type solid)
			)
			(layer "F.CrtYd")
		)
		(fp_line
			(start -1.6 -0.825)
			(end 1.6 -0.825)
			(stroke
				(width 0.2)
				(type solid)
			)
			(layer "F.CrtYd")
		)
		(fp_line
			(start -1.6 -0.825)
			(end -1.6 0.825)
			(stroke
				(width 0.2)
				(type solid)
			)
			(layer "F.CrtYd")
		)
		(fp_line
			(start -1.6 0.825)
			(end 1.6 0.825)
			(stroke
				(width 0.2)
				(type solid)
			)
			(layer "F.CrtYd")
		)
		(fp_line
			(start 1.6 -0.825)
			(end 1.6 0.825)
			(stroke
				(width 0.2)
				(type solid)
			)
			(layer "F.Fab")
		)
		(fp_line
			(start -1.6 -0.825)
			(end 1.6 -0.825)
			(stroke
				(width 0.2)
				(type solid)
			)
			(layer "F.Fab")
		)
		(fp_line
			(start -1.6 -0.825)
			(end -1.6 0.825)
			(stroke
				(width 0.2)
				(type solid)
			)
			(layer "F.Fab")
		)
		(fp_line
			(start 0 -0.5)
			(end 0 0.5)
			(stroke
				(width 0.1)
				(type solid)
			)
			(layer "F.Fab")
		)
		(fp_line
			(start -0.5 0)
			(end 0.5 0)
			(stroke
				(width 0.1)
				(type solid)
			)
			(layer "F.Fab")
		)
		(fp_line
			(start -1.6 0.825)
			(end 1.6 0.825)
			(stroke
				(width 0.2)
				(type solid)
			)
			(layer "F.Fab")
		)
		(fp_text user "${REFERENCE}"
			(at -0.00001 0.09601 90)
			(unlocked yes)
			(layer "F.Fab")
			(effects
				(font
					(face "Arial")
					(size 0.63 0.63)
					(thickness 0.1)
				)
				(justify left bottom)
			)
		)
		(pad "1" smd rect
			(at -1 0 90)
			(size 1 1.25)
			(layers "F.Cu" "F.Mask" "F.Paste")
			(net "+3.3V")
			(solder_mask_margin 0)
			(solder_paste_margin 0)
		)
		(pad "2" smd rect
			(at 1 0 90)
			(size 1 1.25)
			(layers "F.Cu" "F.Mask" "F.Paste")
			(net "GND")
			(solder_mask_margin 0)
			(solder_paste_margin 0)
		)
	)
)
